# T6G (Grand Teton) — schematic netlist excerpt (pin names and nets, part order shuffled) for the footprints in the layout excerpt that follows; sources: Cadence DE-HDL packaged netlist, KiCad conversion of 04192023_DAF0TMB3IC0_F0TG_MB_C_brd_V02_OCP.brd

J69  SCONN288_DDR506112002KQ  IO  pkg DDR288S_1-1VXC  page 93
  VIN_BULK0  = P12V_MEM_CPU0
  RFU0  = NC
  VIN_MGMT  = P3V3_AUX
  HSCL  = I3C_SPD_DDRH_CPU0_SCL
  HSDA  = I3C_SPD_DDRH_CPU0_SDA
  VSS0  = GND
  DQ0_A  = M_H_CPU0_SA_DQ<0>
  VSS1  = GND
  DQ1_A  = M_H_CPU0_SA_DQ<1>
  VSS2  = GND
  DQS0_A_T  = M_H_CPU0_SA_DQS_DP<0>
  DQS0_A_C  = M_H_CPU0_SA_DQS_DN<0>
  VSS3  = GND
  DQ4_A  = M_H_CPU0_SA_DQ<4>
  VSS4  = GND
  DQ5_A  = M_H_CPU0_SA_DQ<5>
  VSS5  = GND
  DQ8_A  = M_H_CPU0_SA_DQ<8>
  VSS6  = GND
  DQ9_A  = M_H_CPU0_SA_DQ<9>
  VSS7  = GND
  DQS1_A_T  = M_H_CPU0_SA_DQS_DP<1>
  DQS1_A_C  = M_H_CPU0_SA_DQS_DN<1>
  VSS8  = GND
  DQ12_A  = M_H_CPU0_SA_DQ<12>
  VSS9  = GND
  DQ13_A  = M_H_CPU0_SA_DQ<13>
  VSS10  = GND
  DQ16_A  = M_H_CPU0_SA_DQ<16>
  VSS11  = GND
  DQ17_A  = M_H_CPU0_SA_DQ<17>
  VSS12  = GND
  DQS2_A_T  = M_H_CPU0_SA_DQS_DP<2>
  DQS2_A_C  = M_H_CPU0_SA_DQS_DN<2>
  VSS13  = GND
  DQ20_A  = M_H_CPU0_SA_DQ<20>
  VSS14  = GND
  DQ21_A  = M_H_CPU0_SA_DQ<21>
  VSS15  = GND
  DQ24_A  = M_H_CPU0_SA_DQ<24>
  VSS16  = GND
  DQ25_A  = M_H_CPU0_SA_DQ<25>
  VSS17  = GND
  DQS3_A_T  = M_H_CPU0_SA_DQS_DP<3>
  DQS3_A_C  = M_H_CPU0_SA_DQS_DN<3>
  VSS18  = GND
  DQ28_A  = M_H_CPU0_SA_DQ<28>
  VSS19  = GND
  DQ29_A  = M_H_CPU0_SA_DQ<29>
  VSS20  = GND
  CB0_A  = M_H_CPU0_SA_CB<0>
  VSS21  = GND
  CB1_A  = M_H_CPU0_SA_CB<1>
  VSS22  = GND
  DQS4_A_T  = M_H_CPU0_SA_DQS_DP<4>
  DQS4_A_C  = M_H_CPU0_SA_DQS_DN<4>
  VSS23  = GND
  CB4_A  = M_H_CPU0_SA_CB<4>
  VSS24  = GND
  CB5_A  = M_H_CPU0_SA_CB<5>
  VSS25  = GND
  ALERT_N  = M_H_CPU0_ALERT_N
  VSS26  = GND
  CS0_A_N  = M_H_CPU0_SA_CS_N<0>
  VSS27  = GND
  CA0_A  = M_H_CPU0_SA_CA<0>
  VSS28  = GND
  CA2_A  = M_H_CPU0_SA_CA<2>
  VSS29  = GND
  CA4_A  = M_H_CPU0_SA_CA<4>
  VSS30  = GND
  CA6_A  = M_H_CPU0_SA_CA<6>
  VSS31  = GND
  PAR_A  = M_H_CPU0_SA_PAR
  VSS32  = GND
  CA0_B  = M_H_CPU0_SB_CA<0>
  VSS33  = GND
  CA2_B  = M_H_CPU0_SB_CA<2>
  VSS34  = GND
  CA4_B  = M_H_CPU0_SB_CA<4>
  VSS35  = GND
  CA6_B  = M_H_CPU0_SB_CA<6>
  VSS36  = GND
  CS0_B_N  = M_H_CPU0_SB_CS_N<0>
  VSS37  = GND
  \lbd||rsp_a_n\  = M_H_CPU0_SA_RSP<0>
  \lbs||rsp_b_n\  = M_H_CPU0_SB_RSP<0>
  VSS38  = GND
  CB4_B  = M_H_CPU0_SB_CB<4>
  VSS39  = GND
  CB5_B  = M_H_CPU0_SB_CB<5>
  VSS40  = GND
  \dqs9_b_t||tdqs9_b_t||dbi4_b_n\  = M_H_CPU0_SB_DQS_DP<9>
  \dqs9_b_c||tdqs9_b_c\  = M_H_CPU0_SB_DQS_DN<9>
  VSS41  = GND
  CB0_B  = M_H_CPU0_SB_CB<0>
  VSS42  = GND
  CB1_B  = M_H_CPU0_SB_CB<1>
  VSS43  = GND
  DQ0_B  = M_H_CPU0_SB_DQ<0>
  VSS44  = GND
  DQ1_B  = M_H_CPU0_SB_DQ<1>
  VSS45  = GND
  DQS0_B_T  = M_H_CPU0_SB_DQS_DP<0>
  DQS0_B_C  = M_H_CPU0_SB_DQS_DN<0>
  VSS46  = GND
  DQ4_B  = M_H_CPU0_SB_DQ<4>
  VSS47  = GND
  DQ5_B  = M_H_CPU0_SB_DQ<5>
  VSS48  = GND
  DQ8_B  = M_H_CPU0_SB_DQ<8>
  VSS49  = GND
  DQ9_B  = M_H_CPU0_SB_DQ<9>
  VSS50  = GND
  DQS1_B_T  = M_H_CPU0_SB_DQS_DP<1>
  DQS1_B_C  = M_H_CPU0_SB_DQS_DN<1>
  VSS51  = GND
  DQ12_B  = M_H_CPU0_SB_DQ<12>
  VSS52  = GND
  DQ13_B  = M_H_CPU0_SB_DQ<13>
  VSS53  = GND
  DQ16_B  = M_H_CPU0_SB_DQ<16>
  VSS54  = GND
  DQ17_B  = M_H_CPU0_SB_DQ<17>
  VSS55  = GND
  DQS2_B_T  = M_H_CPU0_SB_DQS_DP<2>
  DQS2_B_C  = M_H_CPU0_SB_DQS_DN<2>
  VSS56  = GND
  DQ20_B  = M_H_CPU0_SB_DQ<20>
  VSS57  = GND
  DQ21_B  = M_H_CPU0_SB_DQ<21>
  VSS58  = GND
  DQ24_B  = M_H_CPU0_SB_DQ<24>
  VSS59  = GND
  DQ25_B  = M_H_CPU0_SB_DQ<25>
  VSS60  = GND
  DQS3_B_T  = M_H_CPU0_SB_DQS_DP<3>
  DQS3_B_C  = M_H_CPU0_SB_DQS_DN<3>
  VSS61  = GND
  DQ28_B  = M_H_CPU0_SB_DQ<28>
  VSS62  = GND
  DQ29_B  = M_H_CPU0_SB_DQ<29>
  VSS63  = GND
  RFU1  = NC
  VIN_BULK1  = P12V_MEM_CPU0
  VIN_BULK2  = P12V_MEM_CPU0
  \pwr_good||fail_n\  = PWRGD_CHH_CPU0_DIMM
  HAS  = PD_CHH_CPU0_DIMM_SAA
  RFU2  = NC
  RFU3  = NC
  VSS64  = GND
  DQ2_A  = M_H_CPU0_SA_DQ<2>
  VSS65  = GND
  DQ3_A  = M_H_CPU0_SA_DQ<3>
  VSS66  = GND
  \dqs5_a_c||tdqs5_a_c||dqs5_a_t||tdqs5_a_t\  = M_H_CPU0_SA_DQS_DN<5>
  \dqs5_a_t||tdqs5_a_t\  = M_H_CPU0_SA_DQS_DP<5>
  VSS67  = GND
  DQ6_A  = M_H_CPU0_SA_DQ<6>
  VSS68  = GND
  DQ7_A  = M_H_CPU0_SA_DQ<7>
  VSS69  = GND
  DQ10_A  = M_H_CPU0_SA_DQ<10>
  VSS70  = GND
  DQ11_A  = M_H_CPU0_SA_DQ<11>
  VSS71  = GND
  \dqs6_a_c||tdqs6_a_c||dqs6_a_t||tdqs6_a_t\  = M_H_CPU0_SA_DQS_DN<6>
  \dqs6_a_t||tdqs6_a_t\  = M_H_CPU0_SA_DQS_DP<6>
  VSS72  = GND
  DQ14_A  = M_H_CPU0_SA_DQ<14>
  VSS73  = GND
  DQ15_A  = M_H_CPU0_SA_DQ<15>
  VSS74  = GND
  DQ18_A  = M_H_CPU0_SA_DQ<18>
  VSS75  = GND
  DQ19_A  = M_H_CPU0_SA_DQ<19>
  VSS76  = GND
  \dqs7_a_c||tdqs7_a_c\  = M_H_CPU0_SA_DQS_DN<7>
  \dqs7_a_t||tdqs7_a_t\  = M_H_CPU0_SA_DQS_DP<7>
  VSS77  = GND
  DQ22_A  = M_H_CPU0_SA_DQ<22>
  VSS78  = GND
  DQ23_A  = M_H_CPU0_SA_DQ<23>
  VSS79  = GND
  DQ26_A  = M_H_CPU0_SA_DQ<26>
  VSS80  = GND
  DQ27_A  = M_H_CPU0_SA_DQ<27>
  VSS81  = GND
  \dqs8_a_c||tdqs8_a_c\  = M_H_CPU0_SA_DQS_DN<8>
  \dqs8_a_t||tdqs8_a_t\  = M_H_CPU0_SA_DQS_DP<8>
  VSS82  = GND
  DQ30_A  = M_H_CPU0_SA_DQ<30>
  VSS83  = GND
  DQ31_A  = M_H_CPU0_SA_DQ<31>
  VSS84  = GND
  CB2_A  = M_H_CPU0_SA_CB<2>
  VSS85  = GND
  CB3_A  = M_H_CPU0_SA_CB<3>
  VSS86  = GND
  \dqs9_a_c||tdqs9_a_c\  = M_H_CPU0_SA_DQS_DN<9>
  \dqs9_a_t||tdqs9_a_t\  = M_H_CPU0_SA_DQS_DP<9>
  VSS87  = GND
  CB6_A  = M_H_CPU0_SA_CB<6>
  VSS88  = GND
  CB7_A  = M_H_CPU0_SA_CB<7>
  VSS89  = GND
  RESET_N  = M_H_CPU0_RESET_N
  VSS90  = GND
  CS1_A_N  = M_H_CPU0_SA_CS_N<1>
  VSS91  = GND
  CA1_A  = M_H_CPU0_SA_CA<1>
  VSS92  = GND
  CA3_A  = M_H_CPU0_SA_CA<3>
  VSS93  = GND
  CA5_A  = M_H_CPU0_SA_CA<5>
  VSS94  = GND
  CK_T  = M_H_CPU0_CLK_DP<0>
  CK_C  = M_H_CPU0_CLK_DN<0>
  VSS95  = GND
  RFU4  = NC
  CA1_B  = M_H_CPU0_SB_CA<1>
  VSS96  = GND
  CA3_B  = M_H_CPU0_SB_CA<3>
  VSS97  = GND
  CA5_B  = M_H_CPU0_SB_CA<5>
  VSS98  = GND
  PAR_B  = M_H_CPU0_SB_PAR
  VSS99  = GND
  CS1_B_N  = M_H_CPU0_SB_CS_N<1>
  VSS100  = GND
  RFU5  = NC
  RFU6  = NC
  VSS101  = GND
  CB6_B  = M_H_CPU0_SB_CB<6>
  VSS102  = GND
  CB7_B  = M_H_CPU0_SB_CB<7>
  VSS103  = GND
  DQS4_B_C  = M_H_CPU0_SB_DQS_DN<4>
  DQS4_B_T  = M_H_CPU0_SB_DQS_DP<4>
  VSS104  = GND
  CB2_B  = M_H_CPU0_SB_CB<2>
  VSS105  = GND
  CB3_B  = M_H_CPU0_SB_CB<3>
  VSS106  = GND
  DQ2_B  = M_H_CPU0_SB_DQ<2>
  VSS107  = GND
  DQ3_B  = M_H_CPU0_SB_DQ<3>
  VSS108  = GND
  \dqs5_b_c||tdqs5_b_c\  = M_H_CPU0_SB_DQS_DN<5>
  \dqs5_b_t||tdqs5_b_t\  = M_H_CPU0_SB_DQS_DP<5>
  VSS109  = GND
  DQ6_B  = M_H_CPU0_SB_DQ<6>
  VSS110  = GND
  DQ7_B  = M_H_CPU0_SB_DQ<7>
  VSS111  = GND
  DQ10_B  = M_H_CPU0_SB_DQ<10>
  VSS112  = GND
  DQ11_B  = M_H_CPU0_SB_DQ<11>
  VSS113  = GND
  \dqs6_b_c||tdqs6_b_c\  = M_H_CPU0_SB_DQS_DN<6>
  \dqs6_b_t||tdqs6_b_t\  = M_H_CPU0_SB_DQS_DP<6>
  VSS114  = GND
  DQ14_B  = M_H_CPU0_SB_DQ<14>
  VSS115  = GND
  DQ15_B  = M_H_CPU0_SB_DQ<15>
  VSS116  = GND
  DQ18_B  = M_H_CPU0_SB_DQ<18>
  VSS117  = GND
  DQ19_B  = M_H_CPU0_SB_DQ<19>
  VSS118  = GND
  \dqs7_b_c||tdqs7_b_c\  = M_H_CPU0_SB_DQS_DN<7>
  \dqs7_b_t||tdqs7_b_t\  = M_H_CPU0_SB_DQS_DP<7>
  VSS119  = GND
  DQ22_B  = M_H_CPU0_SB_DQ<22>
  VSS120  = GND
  DQ23_B  = M_H_CPU0_SB_DQ<23>
  VSS121  = GND
  DQ26_B  = M_H_CPU0_SB_DQ<26>
  VSS122  = GND
  DQ27_B  = M_H_CPU0_SB_DQ<27>
  VSS123  = GND
  \dqs8_b_c||tdqs8_b_c\  = M_H_CPU0_SB_DQS_DN<8>
  \dqs8_b_t||tdqs8_b_t\  = M_H_CPU0_SB_DQS_DP<8>
  VSS124  = GND
  DQ30_B  = M_H_CPU0_SB_DQ<30>
  VSS125  = GND
  DQ31_B  = M_H_CPU0_SB_DQ<31>
  VSS126  = GND
  G1  = GND
  G2  = GND
  G3  = GND

(kicad_pcb
	(version 20260206)
	(generator "pcbnew")
	(generator_version "10.0")
	(general
		(thickness 1.6)
		(legacy_teardrops no)
	)
	(paper "A4")
	(title_block
		(title "04192023_DAF0TMB3IC0_F0TG_MB_C_brd_V02_OCP.brd")
		(comment 1 "Grand Teton / footprint 2335 of 8354 (J69), pads 47-92 of 291")
	)
	(layers
		(0 "F.Cu" signal "TOP")
		(4 "In1.Cu" signal "GND")
		(6 "In2.Cu" signal "IN1")
		(8 "In3.Cu" signal "GND1")
		(10 "In4.Cu" signal "IN2")
		(12 "In5.Cu" signal "GND2")
		(14 "In6.Cu" signal "IN3")
		(16 "In7.Cu" signal "GND3")
		(18 "In8.Cu" signal "VCC")
		(20 "In9.Cu" signal "VCC1")
		(22 "In10.Cu" signal "GND4")
		(24 "In11.Cu" signal "IN4")
		(26 "In12.Cu" signal "GND5")
		(28 "In13.Cu" signal "IN5")
		(30 "In14.Cu" signal "GND6")
		(32 "In15.Cu" signal "IN6")
		(34 "In16.Cu" signal "GND7")
		(2 "B.Cu" signal "BOTTOM")
		(9 "F.Adhes" user "F.Adhesive")
		(11 "B.Adhes" user "B.Adhesive")
		(13 "F.Paste" user "Package Geometry/Pastemask Top")
		(15 "B.Paste" user "Package Geometry/Pastemask Bottom")
		(5 "F.SilkS" user "Ref Des/Silkscreen Top")
		(7 "B.SilkS" user "Ref Des/Silkscreen Bottom")
		(1 "F.Mask" user "Board Geometry/Soldermask Top")
		(3 "B.Mask" user "Board Geometry/Soldermask Bottom")
		(17 "Dwgs.User" user "User.Drawings")
		(19 "Cmts.User" user "User.Comments")
		(21 "Eco1.User" user "User.Eco1")
		(23 "Eco2.User" user "User.Eco2")
		(25 "Edge.Cuts" user "Board Geometry/Outline")
		(27 "Margin" user)
		(31 "F.CrtYd" user "Package Geometry/Place Bound Top")
		(29 "B.CrtYd" user "Package Geometry/Place Bound Bottom")
		(35 "F.Fab" user "Ref Des/Assembly Top")
		(33 "B.Fab" user "Ref Des/Assembly Bottom")
	)
	(footprint ""
		(layer "F.Cu")
		(at 421.962072 -255.560068 180)
		(property "Reference" "J69"
			(at 3.448304 81.947512 0)
			(unlocked yes)
			(layer "F.SilkS")
			(effects
				(font
					(size 0.7874 0.5842)
					(thickness 0.1524)
				)
			)
		)
		(property "Value" ""
			(at 0 0 180)
			(layer "F.Fab")
			(effects
				(font
					(size 1.27 1.27)
				)
			)
		)
		(duplicate_pad_numbers_are_jumpers no)
		(pad "47" smd rect
			(at -2.050034 -24.224996 90)
			(size 0.519938 1.4986)
			(layers "F.Cu" "F.Mask" "F.Paste")
			(net "M_H_CPU0_SA_DQ<28>")
		)
		(pad "48" smd rect
			(at -2.050034 -23.375112 90)
			(size 0.519938 1.4986)
			(layers "F.Cu" "F.Mask" "F.Paste")
			(net "GND")
		)
		(pad "49" smd rect
			(at -2.050034 -22.524974 90)
			(size 0.519938 1.4986)
			(layers "F.Cu" "F.Mask" "F.Paste")
			(net "M_H_CPU0_SA_DQ<29>")
		)
		(pad "50" smd rect
			(at -2.050034 -21.67509 90)
			(size 0.519938 1.4986)
			(layers "F.Cu" "F.Mask" "F.Paste")
			(net "GND")
		)
		(pad "51" smd rect
			(at -2.050034 -20.824952 90)
			(size 0.519938 1.4986)
			(layers "F.Cu" "F.Mask" "F.Paste")
			(net "M_H_CPU0_SA_CB<0>")
		)
		(pad "52" smd rect
			(at -2.050034 -19.975068 90)
			(size 0.519938 1.4986)
			(layers "F.Cu" "F.Mask" "F.Paste")
			(net "GND")
		)
		(pad "53" smd rect
			(at -2.050034 -19.12493 90)
			(size 0.519938 1.4986)
			(layers "F.Cu" "F.Mask" "F.Paste")
			(net "M_H_CPU0_SA_CB<1>")
		)
		(pad "54" smd rect
			(at -2.050034 -18.275046 90)
			(size 0.519938 1.4986)
			(layers "F.Cu" "F.Mask" "F.Paste")
			(net "GND")
		)
		(pad "55" smd rect
			(at -2.050034 -17.424908 90)
			(size 0.519938 1.4986)
			(layers "F.Cu" "F.Mask" "F.Paste")
			(net "M_H_CPU0_SA_DQS_DP<4>")
		)
		(pad "56" smd rect
			(at -2.050034 -16.575024 90)
			(size 0.519938 1.4986)
			(layers "F.Cu" "F.Mask" "F.Paste")
			(net "M_H_CPU0_SA_DQS_DN<4>")
		)
		(pad "57" smd rect
			(at -2.050034 -15.724886 90)
			(size 0.519938 1.4986)
			(layers "F.Cu" "F.Mask" "F.Paste")
			(net "GND")
		)
		(pad "58" smd rect
			(at -2.050034 -14.875002 90)
			(size 0.519938 1.4986)
			(layers "F.Cu" "F.Mask" "F.Paste")
			(net "M_H_CPU0_SA_CB<4>")
		)
		(pad "59" smd rect
			(at -2.050034 -14.025118 90)
			(size 0.519938 1.4986)
			(layers "F.Cu" "F.Mask" "F.Paste")
			(net "GND")
		)
		(pad "60" smd rect
			(at -2.050034 -13.17498 90)
			(size 0.519938 1.4986)
			(layers "F.Cu" "F.Mask" "F.Paste")
			(net "M_H_CPU0_SA_CB<5>")
		)
		(pad "61" smd rect
			(at -2.050034 -12.325096 90)
			(size 0.519938 1.4986)
			(layers "F.Cu" "F.Mask" "F.Paste")
			(net "GND")
		)
		(pad "62" smd rect
			(at -2.050034 -11.474958 90)
			(size 0.519938 1.4986)
			(layers "F.Cu" "F.Mask" "F.Paste")
			(net "M_H_CPU0_ALERT_N")
		)
		(pad "63" smd rect
			(at -2.050034 -10.625074 90)
			(size 0.519938 1.4986)
			(layers "F.Cu" "F.Mask" "F.Paste")
			(net "GND")
		)
		(pad "64" smd rect
			(at -2.050034 -9.774936 90)
			(size 0.519938 1.4986)
			(layers "F.Cu" "F.Mask" "F.Paste")
			(net "M_H_CPU0_SA_CS_N<0>")
		)
		(pad "65" smd rect
			(at -2.050034 -8.925052 90)
			(size 0.519938 1.4986)
			(layers "F.Cu" "F.Mask" "F.Paste")
			(net "GND")
		)
		(pad "66" smd rect
			(at -2.050034 -8.074914 90)
			(size 0.519938 1.4986)
			(layers "F.Cu" "F.Mask" "F.Paste")
			(net "M_H_CPU0_SA_CA<0>")
		)
		(pad "67" smd rect
			(at -2.050034 -7.22503 90)
			(size 0.519938 1.4986)
			(layers "F.Cu" "F.Mask" "F.Paste")
			(net "GND")
		)
		(pad "68" smd rect
			(at -2.050034 -6.374892 90)
			(size 0.519938 1.4986)
			(layers "F.Cu" "F.Mask" "F.Paste")
			(net "M_H_CPU0_SA_CA<2>")
		)
		(pad "69" smd rect
			(at -2.050034 -5.525008 90)
			(size 0.519938 1.4986)
			(layers "F.Cu" "F.Mask" "F.Paste")
			(net "GND")
		)
		(pad "70" smd rect
			(at -2.050034 -4.675124 90)
			(size 0.519938 1.4986)
			(layers "F.Cu" "F.Mask" "F.Paste")
			(net "M_H_CPU0_SA_CA<4>")
		)
		(pad "71" smd rect
			(at -2.050034 -3.824986 90)
			(size 0.519938 1.4986)
			(layers "F.Cu" "F.Mask" "F.Paste")
			(net "GND")
		)
		(pad "72" smd rect
			(at -2.050034 -2.975102 90)
			(size 0.519938 1.4986)
			(layers "F.Cu" "F.Mask" "F.Paste")
			(net "M_H_CPU0_SA_CA<6>")
		)
		(pad "73" smd rect
			(at -2.050034 -2.124964 90)
			(size 0.519938 1.4986)
			(layers "F.Cu" "F.Mask" "F.Paste")
			(net "GND")
		)
		(pad "74" smd rect
			(at -2.050034 -1.27508 90)
			(size 0.519938 1.4986)
			(layers "F.Cu" "F.Mask" "F.Paste")
			(net "M_H_CPU0_SA_PAR")
		)
		(pad "75" smd rect
			(at -2.050034 -0.424942 90)
			(size 0.519938 1.4986)
			(layers "F.Cu" "F.Mask" "F.Paste")
			(net "GND")
		)
		(pad "76" smd rect
			(at -2.050034 5.525008 90)
			(size 0.519938 1.4986)
			(layers "F.Cu" "F.Mask" "F.Paste")
			(net "M_H_CPU0_SB_CA<0>")
		)
		(pad "77" smd rect
			(at -2.050034 6.374892 90)
			(size 0.519938 1.4986)
			(layers "F.Cu" "F.Mask" "F.Paste")
			(net "GND")
		)
		(pad "78" smd rect
			(at -2.050034 7.22503 90)
			(size 0.519938 1.4986)
			(layers "F.Cu" "F.Mask" "F.Paste")
			(net "M_H_CPU0_SB_CA<2>")
		)
		(pad "79" smd rect
			(at -2.050034 8.074914 90)
			(size 0.519938 1.4986)
			(layers "F.Cu" "F.Mask" "F.Paste")
			(net "GND")
		)
		(pad "80" smd rect
			(at -2.050034 8.925052 90)
			(size 0.519938 1.4986)
			(layers "F.Cu" "F.Mask" "F.Paste")
			(net "M_H_CPU0_SB_CA<4>")
		)
		(pad "81" smd rect
			(at -2.050034 9.774936 90)
			(size 0.519938 1.4986)
			(layers "F.Cu" "F.Mask" "F.Paste")
			(net "GND")
		)
		(pad "82" smd rect
			(at -2.050034 10.625074 90)
			(size 0.519938 1.4986)
			(layers "F.Cu" "F.Mask" "F.Paste")
			(net "M_H_CPU0_SB_CA<6>")
		)
		(pad "83" smd rect
			(at -2.050034 11.474958 90)
			(size 0.519938 1.4986)
			(layers "F.Cu" "F.Mask" "F.Paste")
			(net "GND")
		)
		(pad "84" smd rect
			(at -2.050034 12.325096 90)
			(size 0.519938 1.4986)
			(layers "F.Cu" "F.Mask" "F.Paste")
			(net "M_H_CPU0_SB_CS_N<0>")
		)
		(pad "85" smd rect
			(at -2.050034 13.17498 90)
			(size 0.519938 1.4986)
			(layers "F.Cu" "F.Mask" "F.Paste")
			(net "GND")
		)
		(pad "86" smd rect
			(at -2.050034 14.025118 90)
			(size 0.519938 1.4986)
			(layers "F.Cu" "F.Mask" "F.Paste")
			(net "M_H_CPU0_SA_RSP<0>")
		)
		(pad "87" smd rect
			(at -2.050034 14.875002 90)
			(size 0.519938 1.4986)
			(layers "F.Cu" "F.Mask" "F.Paste")
			(net "M_H_CPU0_SB_RSP<0>")
		)
		(pad "88" smd rect
			(at -2.050034 15.724886 90)
			(size 0.519938 1.4986)
			(layers "F.Cu" "F.Mask" "F.Paste")
			(net "GND")
		)
		(pad "89" smd rect
			(at -2.050034 16.575024 90)
			(size 0.519938 1.4986)
			(layers "F.Cu" "F.Mask" "F.Paste")
			(net "M_H_CPU0_SB_CB<4>")
		)
		(pad "90" smd rect
			(at -2.050034 17.424908 90)
			(size 0.519938 1.4986)
			(layers "F.Cu" "F.Mask" "F.Paste")
			(net "GND")
		)
		(pad "91" smd rect
			(at -2.050034 18.275046 90)
			(size 0.519938 1.4986)
			(layers "F.Cu" "F.Mask" "F.Paste")
			(net "M_H_CPU0_SB_CB<5>")
		)
		(pad "92" smd rect
			(at -2.050034 19.12493 90)
			(size 0.519938 1.4986)
			(layers "F.Cu" "F.Mask" "F.Paste")
			(net "GND")
		)
	)
)
